(kicad_pcb
	(version 20260206)
	(generator "pcbnew")
	(generator_version "10.0")
	(general
		(thickness 1.6)
		(legacy_teardrops no)
	)
	(paper "A4")
	(title_block
		(title "01162023_DA0F0TEBIF0_F0T_Expander_BD_F_brd_V02_OCP.brd")
		(comment 1 "Grand Teton / footprints 9706-9713 of 9728")
	)
	(layers
		(0 "F.Cu" signal "TOP")
		(4 "In1.Cu" signal "GND")
		(6 "In2.Cu" signal "VCC")
		(8 "In3.Cu" signal "VCC1")
		(10 "In4.Cu" signal "GND1")
		(12 "In5.Cu" signal "IN1")
		(14 "In6.Cu" signal "GND2")
		(16 "In7.Cu" signal "IN2")
		(18 "In8.Cu" signal "GND3")
		(20 "In9.Cu" signal "IN3")
		(22 "In10.Cu" signal "GND4")
		(24 "In11.Cu" signal "IN4")
		(26 "In12.Cu" signal "GND5")
		(28 "In13.Cu" signal "IN5")
		(30 "In14.Cu" signal "GND6")
		(32 "In15.Cu" signal "IN6")
		(34 "In16.Cu" signal "GND7")
		(2 "B.Cu" signal "BOTTOM")
		(9 "F.Adhes" user "F.Adhesive")
		(11 "B.Adhes" user "B.Adhesive")
		(13 "F.Paste" user "Package Geometry/Pastemask Top")
		(15 "B.Paste" user "Package Geometry/Pastemask Bottom")
		(5 "F.SilkS" user "Ref Des/Silkscreen Top")
		(7 "B.SilkS" user "Ref Des/Silkscreen Bottom")
		(1 "F.Mask" user "Board Geometry/Soldermask Top")
		(3 "B.Mask" user "Board Geometry/Soldermask Bottom")
		(17 "Dwgs.User" user "User.Drawings")
		(19 "Cmts.User" user "User.Comments")
		(21 "Eco1.User" user "User.Eco1")
		(23 "Eco2.User" user "User.Eco2")
		(25 "Edge.Cuts" user "Board Geometry/Outline")
		(27 "Margin" user)
		(31 "F.CrtYd" user "Package Geometry/Place Bound Top")
		(29 "B.CrtYd" user "Package Geometry/Place Bound Bottom")
		(35 "F.Fab" user "Ref Des/Assembly Top")
		(33 "B.Fab" user "Ref Des/Assembly Bottom")
	)
	(footprint ""
		(layer "B.Cu")
		(at 145.804382 -225.76663 180)
		(property "Reference" "R6166"
			(at 0 0 0)
			(layer "B.SilkS")
			(hide yes)
			(effects
				(font
					(size 1.27 1.27)
				)
				(justify mirror)
			)
		)
		(property "Value" ""
			(at 0 0 0)
			(layer "B.Fab")
			(effects
				(font
					(size 1.27 1.27)
				)
				(justify mirror)
			)
		)
		(duplicate_pad_numbers_are_jumpers no)
		(fp_line
			(start 0.7874 0.4064)
			(end 0.7874 -0.4064)
			(stroke
				(width 0.1524)
				(type default)
			)
			(layer "B.SilkS")
		)
		(fp_line
			(start 0.7874 -0.4064)
			(end -0.7874 -0.4064)
			(stroke
				(width 0.1524)
				(type default)
			)
			(layer "B.SilkS")
		)
		(fp_line
			(start -0.7874 0.4064)
			(end 0.7874 0.4064)
			(stroke
				(width 0.1524)
				(type default)
			)
			(layer "B.SilkS")
		)
		(fp_line
			(start -0.7874 -0.4064)
			(end -0.7874 0.4064)
			(stroke
				(width 0.1524)
				(type default)
			)
			(layer "B.SilkS")
		)
		(fp_line
			(start 0.67945 0.3048)
			(end 0.67945 -0.305054)
			(stroke
				(width 0.1)
				(type default)
			)
			(layer "B.Fab")
		)
		(fp_line
			(start 0.67945 -0.305054)
			(end 0.12065 -0.305054)
			(stroke
				(width 0.1)
				(type default)
			)
			(layer "B.Fab")
		)
		(fp_line
			(start 0.12065 0.3048)
			(end 0.67945 0.3048)
			(stroke
				(width 0.1)
				(type default)
			)
			(layer "B.Fab")
		)
		(fp_line
			(start 0.12065 0.2794)
			(end 0.12065 0.3048)
			(stroke
				(width 0.1)
				(type default)
			)
			(layer "B.Fab")
		)
		(fp_line
			(start 0.12065 -0.2794)
			(end -0.12065 -0.2794)
			(stroke
				(width 0.1)
				(type default)
			)
			(layer "B.Fab")
		)
		(fp_line
			(start 0.12065 -0.305054)
			(end 0.12065 -0.2794)
			(stroke
				(width 0.1)
				(type default)
			)
			(layer "B.Fab")
		)
		(fp_line
			(start -0.120396 0.3048)
			(end -0.120396 0.2794)
			(stroke
				(width 0.1)
				(type default)
			)
			(layer "B.Fab")
		)
		(fp_line
			(start -0.120396 0.2794)
			(end 0.12065 0.2794)
			(stroke
				(width 0.1)
				(type default)
			)
			(layer "B.Fab")
		)
		(fp_line
			(start -0.12065 -0.2794)
			(end -0.12065 -0.3048)
			(stroke
				(width 0.1)
				(type default)
			)
			(layer "B.Fab")
		)
		(fp_line
			(start -0.12065 -0.3048)
			(end -0.67945 -0.3048)
			(stroke
				(width 0.1)
				(type default)
			)
			(layer "B.Fab")
		)
		(fp_line
			(start -0.67945 0.3048)
			(end -0.120396 0.3048)
			(stroke
				(width 0.1)
				(type default)
			)
			(layer "B.Fab")
		)
		(fp_line
			(start -0.67945 -0.3048)
			(end -0.67945 0.3048)
			(stroke
				(width 0.1)
				(type default)
			)
			(layer "B.Fab")
		)
		(pad "1" smd circle
			(at 0.40005 0)
			(size 0 0)
			(layers "B.Cu" "B.Mask" "B.Paste")
			(net "SPI_PEX1_RST_R_N")
		)
		(pad "2" smd circle
			(at -0.40005 0)
			(size 0 0)
			(layers "B.Cu" "B.Mask" "B.Paste")
			(net "P1V8_PEX")
		)
	)
	(footprint ""
		(layer "B.Cu")
		(at 241.060732 -234.051094 90)
		(property "Reference" "R6816"
			(at 0 0 90)
			(layer "B.SilkS")
			(hide yes)
			(effects
				(font
					(size 1.27 1.27)
				)
				(justify mirror)
			)
		)
		(property "Value" ""
			(at 0 0 90)
			(layer "B.Fab")
			(effects
				(font
					(size 1.27 1.27)
				)
				(justify mirror)
			)
		)
		(duplicate_pad_numbers_are_jumpers no)
		(fp_line
			(start 0.7874 -0.4064)
			(end -0.7874 -0.4064)
			(stroke
				(width 0.1524)
				(type default)
			)
			(layer "B.SilkS")
		)
		(fp_line
			(start -0.7874 -0.4064)
			(end -0.7874 0.4064)
			(stroke
				(width 0.1524)
				(type default)
			)
			(layer "B.SilkS")
		)
		(fp_line
			(start 0.7874 0.4064)
			(end 0.7874 -0.4064)
			(stroke
				(width 0.1524)
				(type default)
			)
			(layer "B.SilkS")
		)
		(fp_line
			(start -0.7874 0.4064)
			(end 0.7874 0.4064)
			(stroke
				(width 0.1524)
				(type default)
			)
			(layer "B.SilkS")
		)
		(fp_line
			(start 0.67945 -0.305054)
			(end 0.12065 -0.305054)
			(stroke
				(width 0.1)
				(type default)
			)
			(layer "B.Fab")
		)
		(fp_line
			(start 0.12065 -0.305054)
			(end 0.12065 -0.2794)
			(stroke
				(width 0.1)
				(type default)
			)
			(layer "B.Fab")
		)
		(fp_line
			(start -0.12065 -0.3048)
			(end -0.67945 -0.3048)
			(stroke
				(width 0.1)
				(type default)
			)
			(layer "B.Fab")
		)
		(fp_line
			(start -0.67945 -0.3048)
			(end -0.67945 0.3048)
			(stroke
				(width 0.1)
				(type default)
			)
			(layer "B.Fab")
		)
		(fp_line
			(start 0.12065 -0.2794)
			(end -0.12065 -0.2794)
			(stroke
				(width 0.1)
				(type default)
			)
			(layer "B.Fab")
		)
		(fp_line
			(start -0.12065 -0.2794)
			(end -0.12065 -0.3048)
			(stroke
				(width 0.1)
				(type default)
			)
			(layer "B.Fab")
		)
		(fp_line
			(start 0.12065 0.2794)
			(end 0.12065 0.3048)
			(stroke
				(width 0.1)
				(type default)
			)
			(layer "B.Fab")
		)
		(fp_line
			(start -0.120396 0.2794)
			(end 0.12065 0.2794)
			(stroke
				(width 0.1)
				(type default)
			)
			(layer "B.Fab")
		)
		(fp_line
			(start 0.67945 0.3048)
			(end 0.67945 -0.305054)
			(stroke
				(width 0.1)
				(type default)
			)
			(layer "B.Fab")
		)
		(fp_line
			(start 0.12065 0.3048)
			(end 0.67945 0.3048)
			(stroke
				(width 0.1)
				(type default)
			)
			(layer "B.Fab")
		)
		(fp_line
			(start -0.120396 0.3048)
			(end -0.120396 0.2794)
			(stroke
				(width 0.1)
				(type default)
			)
			(layer "B.Fab")
		)
		(fp_line
			(start -0.67945 0.3048)
			(end -0.120396 0.3048)
			(stroke
				(width 0.1)
				(type default)
			)
			(layer "B.Fab")
		)
		(pad "1" smd circle
			(at 0.40005 0 270)
			(size 0 0)
			(layers "B.Cu" "B.Mask" "B.Paste")
			(net "GND")
		)
		(pad "2" smd circle
			(at -0.40005 0 270)
			(size 0 0)
			(layers "B.Cu" "B.Mask" "B.Paste")
			(net "BOARD_TYPE_2_ADC_R")
		)
	)
	(footprint ""
		(layer "B.Cu")
		(at 290.89985 -290.199826 90)
		(property "Reference" "C1690"
			(at 0 0 90)
			(layer "B.SilkS")
			(hide yes)
			(effects
				(font
					(size 1.27 1.27)
				)
				(justify mirror)
			)
		)
		(property "Value" ""
			(at 0 0 90)
			(layer "B.Fab")
			(effects
				(font
					(size 1.27 1.27)
				)
				(justify mirror)
			)
		)
		(duplicate_pad_numbers_are_jumpers no)
		(fp_line
			(start 0.299974 -0.150114)
			(end -0.299974 -0.150114)
			(stroke
				(width 0.1)
				(type default)
			)
			(layer "B.Fab")
		)
		(fp_line
			(start -0.299974 -0.150114)
			(end -0.299974 0.150114)
			(stroke
				(width 0.1)
				(type default)
			)
			(layer "B.Fab")
		)
		(fp_line
			(start 0.299974 0.150114)
			(end 0.299974 -0.150114)
			(stroke
				(width 0.1)
				(type default)
			)
			(layer "B.Fab")
		)
		(fp_line
			(start -0.299974 0.150114)
			(end 0.299974 0.150114)
			(stroke
				(width 0.1)
				(type default)
			)
			(layer "B.Fab")
		)
		(pad "1" smd rect
			(at 0.2667 0 270)
			(size 0.3048 0.381)
			(layers "B.Cu" "B.Mask" "B.Paste")
			(net "P0V8_SERDES_VDDA_PEX2")
		)
		(pad "2" smd rect
			(at -0.2667 0 270)
			(size 0.3048 0.381)
			(layers "B.Cu" "B.Mask" "B.Paste")
			(net "GND")
		)
	)
	(footprint ""
		(layer "B.Cu")
		(at 351.645982 -154.305)
		(property "Reference" "R4806"
			(at 0 0 0)
			(layer "B.SilkS")
			(hide yes)
			(effects
				(font
					(size 1.27 1.27)
				)
				(justify mirror)
			)
		)
		(property "Value" ""
			(at 0 0 0)
			(layer "B.Fab")
			(effects
				(font
					(size 1.27 1.27)
				)
				(justify mirror)
			)
		)
		(duplicate_pad_numbers_are_jumpers no)
		(fp_line
			(start -0.7874 -0.4064)
			(end -0.7874 0.4064)
			(stroke
				(width 0.1524)
				(type default)
			)
			(layer "B.SilkS")
		)
		(fp_line
			(start -0.7874 0.4064)
			(end 0.7874 0.4064)
			(stroke
				(width 0.1524)
				(type default)
			)
			(layer "B.SilkS")
		)
		(fp_line
			(start 0.7874 -0.4064)
			(end -0.7874 -0.4064)
			(stroke
				(width 0.1524)
				(type default)
			)
			(layer "B.SilkS")
		)
		(fp_line
			(start 0.7874 0.4064)
			(end 0.7874 -0.4064)
			(stroke
				(width 0.1524)
				(type default)
			)
			(layer "B.SilkS")
		)
		(fp_line
			(start -0.67945 -0.3048)
			(end -0.67945 0.3048)
			(stroke
				(width 0.1)
				(type default)
			)
			(layer "B.Fab")
		)
		(fp_line
			(start -0.67945 0.3048)
			(end -0.120396 0.3048)
			(stroke
				(width 0.1)
				(type default)
			)
			(layer "B.Fab")
		)
		(fp_line
			(start -0.12065 -0.3048)
			(end -0.67945 -0.3048)
			(stroke
				(width 0.1)
				(type default)
			)
			(layer "B.Fab")
		)
		(fp_line
			(start -0.12065 -0.2794)
			(end -0.12065 -0.3048)
			(stroke
				(width 0.1)
				(type default)
			)
			(layer "B.Fab")
		)
		(fp_line
			(start -0.120396 0.2794)
			(end 0.12065 0.2794)
			(stroke
				(width 0.1)
				(type default)
			)
			(layer "B.Fab")
		)
		(fp_line
			(start -0.120396 0.3048)
			(end -0.120396 0.2794)
			(stroke
				(width 0.1)
				(type default)
			)
			(layer "B.Fab")
		)
		(fp_line
			(start 0.12065 -0.305054)
			(end 0.12065 -0.2794)
			(stroke
				(width 0.1)
				(type default)
			)
			(layer "B.Fab")
		)
		(fp_line
			(start 0.12065 -0.2794)
			(end -0.12065 -0.2794)
			(stroke
				(width 0.1)
				(type default)
			)
			(layer "B.Fab")
		)
		(fp_line
			(start 0.12065 0.2794)
			(end 0.12065 0.3048)
			(stroke
				(width 0.1)
				(type default)
			)
			(layer "B.Fab")
		)
		(fp_line
			(start 0.12065 0.3048)
			(end 0.67945 0.3048)
			(stroke
				(width 0.1)
				(type default)
			)
			(layer "B.Fab")
		)
		(fp_line
			(start 0.67945 -0.305054)
			(end 0.12065 -0.305054)
			(stroke
				(width 0.1)
				(type default)
			)
			(layer "B.Fab")
		)
		(fp_line
			(start 0.67945 0.3048)
			(end 0.67945 -0.305054)
			(stroke
				(width 0.1)
				(type default)
			)
			(layer "B.Fab")
		)
		(pad "1" smd circle
			(at 0.40005 0 180)
			(size 0 0)
			(layers "B.Cu" "B.Mask" "B.Paste")
			(net "NIC6_PEX_PWR_EN_R")
		)
		(pad "2" smd circle
			(at -0.40005 0 180)
			(size 0 0)
			(layers "B.Cu" "B.Mask" "B.Paste")
			(net "GND")
		)
	)
	(footprint ""
		(layer "B.Cu")
		(at 296.599864 -301.599854 -90)
		(property "Reference" "C1717"
			(at 0 0 90)
			(layer "B.SilkS")
			(hide yes)
			(effects
				(font
					(size 1.27 1.27)
				)
				(justify mirror)
			)
		)
		(property "Value" ""
			(at 0 0 90)
			(layer "B.Fab")
			(effects
				(font
					(size 1.27 1.27)
				)
				(justify mirror)
			)
		)
		(duplicate_pad_numbers_are_jumpers no)
		(fp_line
			(start -0.299974 0.150114)
			(end 0.299974 0.150114)
			(stroke
				(width 0.1)
				(type default)
			)
			(layer "B.Fab")
		)
		(fp_line
			(start 0.299974 0.150114)
			(end 0.299974 -0.150114)
			(stroke
				(width 0.1)
				(type default)
			)
			(layer "B.Fab")
		)
		(fp_line
			(start -0.299974 -0.150114)
			(end -0.299974 0.150114)
			(stroke
				(width 0.1)
				(type default)
			)
			(layer "B.Fab")
		)
		(fp_line
			(start 0.299974 -0.150114)
			(end -0.299974 -0.150114)
			(stroke
				(width 0.1)
				(type default)
			)
			(layer "B.Fab")
		)
		(pad "1" smd rect
			(at 0.2667 0 90)
			(size 0.3048 0.381)
			(layers "B.Cu" "B.Mask" "B.Paste")
			(net "P0V8_SERDES_VDDA_PEX2")
		)
		(pad "2" smd rect
			(at -0.2667 0 90)
			(size 0.3048 0.381)
			(layers "B.Cu" "B.Mask" "B.Paste")
			(net "GND")
		)
	)
	(footprint ""
		(layer "B.Cu")
		(at 408.424888 -286.399732 90)
		(property "Reference" "C3479"
			(at 0 0 90)
			(layer "B.SilkS")
			(hide yes)
			(effects
				(font
					(size 1.27 1.27)
				)
				(justify mirror)
			)
		)
		(property "Value" ""
			(at 0 0 90)
			(layer "B.Fab")
			(effects
				(font
					(size 1.27 1.27)
				)
				(justify mirror)
			)
		)
		(duplicate_pad_numbers_are_jumpers no)
		(fp_line
			(start 0.299974 -0.150114)
			(end -0.299974 -0.150114)
			(stroke
				(width 0.1)
				(type default)
			)
			(layer "B.Fab")
		)
		(fp_line
			(start -0.299974 -0.150114)
			(end -0.299974 0.150114)
			(stroke
				(width 0.1)
				(type default)
			)
			(layer "B.Fab")
		)
		(fp_line
			(start 0.299974 0.150114)
			(end 0.299974 -0.150114)
			(stroke
				(width 0.1)
				(type default)
			)
			(layer "B.Fab")
		)
		(fp_line
			(start -0.299974 0.150114)
			(end 0.299974 0.150114)
			(stroke
				(width 0.1)
				(type default)
			)
			(layer "B.Fab")
		)
		(pad "1" smd rect
			(at 0.2667 0 270)
			(size 0.3048 0.381)
			(layers "B.Cu" "B.Mask" "B.Paste")
			(net "P1V25_SERDES_VDDPLL_PEX3")
		)
		(pad "2" smd rect
			(at -0.2667 0 270)
			(size 0.3048 0.381)
			(layers "B.Cu" "B.Mask" "B.Paste")
			(net "GND")
		)
	)
	(footprint ""
		(layer "B.Cu")
		(at 384.409696 -247.311926 90)
		(property "Reference" "R938"
			(at 0 0 90)
			(layer "B.SilkS")
			(hide yes)
			(effects
				(font
					(size 1.27 1.27)
				)
				(justify mirror)
			)
		)
		(property "Value" ""
			(at 0 0 90)
			(layer "B.Fab")
			(effects
				(font
					(size 1.27 1.27)
				)
				(justify mirror)
			)
		)
		(duplicate_pad_numbers_are_jumpers no)
		(fp_line
			(start 0.7874 -0.4064)
			(end -0.7874 -0.4064)
			(stroke
				(width 0.1524)
				(type default)
			)
			(layer "B.SilkS")
		)
		(fp_line
			(start -0.7874 -0.4064)
			(end -0.7874 0.4064)
			(stroke
				(width 0.1524)
				(type default)
			)
			(layer "B.SilkS")
		)
		(fp_line
			(start 0.7874 0.4064)
			(end 0.7874 -0.4064)
			(stroke
				(width 0.1524)
				(type default)
			)
			(layer "B.SilkS")
		)
		(fp_line
			(start -0.7874 0.4064)
			(end 0.7874 0.4064)
			(stroke
				(width 0.1524)
				(type default)
			)
			(layer "B.SilkS")
		)
		(fp_line
			(start 0.67945 -0.305054)
			(end 0.12065 -0.305054)
			(stroke
				(width 0.1)
				(type default)
			)
			(layer "B.Fab")
		)
		(fp_line
			(start 0.12065 -0.305054)
			(end 0.12065 -0.2794)
			(stroke
				(width 0.1)
				(type default)
			)
			(layer "B.Fab")
		)
		(fp_line
			(start -0.12065 -0.3048)
			(end -0.67945 -0.3048)
			(stroke
				(width 0.1)
				(type default)
			)
			(layer "B.Fab")
		)
		(fp_line
			(start -0.67945 -0.3048)
			(end -0.67945 0.3048)
			(stroke
				(width 0.1)
				(type default)
			)
			(layer "B.Fab")
		)
		(fp_line
			(start 0.12065 -0.2794)
			(end -0.12065 -0.2794)
			(stroke
				(width 0.1)
				(type default)
			)
			(layer "B.Fab")
		)
		(fp_line
			(start -0.12065 -0.2794)
			(end -0.12065 -0.3048)
			(stroke
				(width 0.1)
				(type default)
			)
			(layer "B.Fab")
		)
		(fp_line
			(start 0.12065 0.2794)
			(end 0.12065 0.3048)
			(stroke
				(width 0.1)
				(type default)
			)
			(layer "B.Fab")
		)
		(fp_line
			(start -0.120396 0.2794)
			(end 0.12065 0.2794)
			(stroke
				(width 0.1)
				(type default)
			)
			(layer "B.Fab")
		)
		(fp_line
			(start 0.67945 0.3048)
			(end 0.67945 -0.305054)
			(stroke
				(width 0.1)
				(type default)
			)
			(layer "B.Fab")
		)
		(fp_line
			(start 0.12065 0.3048)
			(end 0.67945 0.3048)
			(stroke
				(width 0.1)
				(type default)
			)
			(layer "B.Fab")
		)
		(fp_line
			(start -0.120396 0.3048)
			(end -0.120396 0.2794)
			(stroke
				(width 0.1)
				(type default)
			)
			(layer "B.Fab")
		)
		(fp_line
			(start -0.67945 0.3048)
			(end -0.120396 0.3048)
			(stroke
				(width 0.1)
				(type default)
			)
			(layer "B.Fab")
		)
		(pad "1" smd circle
			(at 0.40005 0 270)
			(size 0 0)
			(layers "B.Cu" "B.Mask" "B.Paste")
			(net "UART_PEX3_SDB_BUF_RX")
		)
		(pad "2" smd circle
			(at -0.40005 0 270)
			(size 0 0)
			(layers "B.Cu" "B.Mask" "B.Paste")
			(net "P1V8_PEX")
		)
	)
	(footprint ""
		(layer "B.Cu")
		(at 137.846816 -211.045806)
		(property "Reference" "C2587"
			(at 0 0 0)
			(layer "B.SilkS")
			(hide yes)
			(effects
				(font
					(size 1.27 1.27)
				)
				(justify mirror)
			)
		)
		(property "Value" ""
			(at 0 0 0)
			(layer "B.Fab")
			(effects
				(font
					(size 1.27 1.27)
				)
				(justify mirror)
			)
		)
		(duplicate_pad_numbers_are_jumpers no)
		(fp_line
			(start -0.7874 -0.4064)
			(end -0.7874 0.4064)
			(stroke
				(width 0.1524)
				(type default)
			)
			(layer "B.SilkS")
		)
		(fp_line
			(start -0.7874 0.4064)
			(end 0.7874 0.4064)
			(stroke
				(width 0.1524)
				(type default)
			)
			(layer "B.SilkS")
		)
		(fp_line
			(start 0.7874 -0.4064)
			(end -0.7874 -0.4064)
			(stroke
				(width 0.1524)
				(type default)
			)
			(layer "B.SilkS")
		)
		(fp_line
			(start 0.7874 0.4064)
			(end 0.7874 -0.4064)
			(stroke
				(width 0.1524)
				(type default)
			)
			(layer "B.SilkS")
		)
		(fp_line
			(start -0.67945 -0.3048)
			(end -0.67945 0.3048)
			(stroke
				(width 0.1)
				(type default)
			)
			(layer "B.Fab")
		)
		(fp_line
			(start -0.67945 0.3048)
			(end -0.120396 0.3048)
			(stroke
				(width 0.1)
				(type default)
			)
			(layer "B.Fab")
		)
		(fp_line
			(start -0.12065 -0.3048)
			(end -0.67945 -0.3048)
			(stroke
				(width 0.1)
				(type default)
			)
			(layer "B.Fab")
		)
		(fp_line
			(start -0.12065 -0.2794)
			(end -0.12065 -0.3048)
			(stroke
				(width 0.1)
				(type default)
			)
			(layer "B.Fab")
		)
		(fp_line
			(start -0.120396 0.2794)
			(end 0.12065 0.2794)
			(stroke
				(width 0.1)
				(type default)
			)
			(layer "B.Fab")
		)
		(fp_line
			(start -0.120396 0.3048)
			(end -0.120396 0.2794)
			(stroke
				(width 0.1)
				(type default)
			)
			(layer "B.Fab")
		)
		(fp_line
			(start 0.12065 -0.305054)
			(end 0.12065 -0.2794)
			(stroke
				(width 0.1)
				(type default)
			)
			(layer "B.Fab")
		)
		(fp_line
			(start 0.12065 -0.2794)
			(end -0.12065 -0.2794)
			(stroke
				(width 0.1)
				(type default)
			)
			(layer "B.Fab")
		)
		(fp_line
			(start 0.12065 0.2794)
			(end 0.12065 0.3048)
			(stroke
				(width 0.1)
				(type default)
			)
			(layer "B.Fab")
		)
		(fp_line
			(start 0.12065 0.3048)
			(end 0.67945 0.3048)
			(stroke
				(width 0.1)
				(type default)
			)
			(layer "B.Fab")
		)
		(fp_line
			(start 0.67945 -0.305054)
			(end 0.12065 -0.305054)
			(stroke
				(width 0.1)
				(type default)
			)
			(layer "B.Fab")
		)
		(fp_line
			(start 0.67945 0.3048)
			(end 0.67945 -0.305054)
			(stroke
				(width 0.1)
				(type default)
			)
			(layer "B.Fab")
		)
		(pad "1" smd circle
			(at 0.40005 0 180)
			(size 0 0)
			(layers "B.Cu" "B.Mask" "B.Paste")
			(net "P3V3_AUX")
		)
		(pad "2" smd circle
			(at -0.40005 0 180)
			(size 0 0)
			(layers "B.Cu" "B.Mask" "B.Paste")
			(net "GND")
		)
	)
)
